FILE_TYPE=LIBRARY_PARTS;
primitive 'CONN72_G97614002_A','CONN72_G97614002_A_CP';
  pin
    'GND'<23>:
      PIN_NUMBER='(1A3)';
      PINUSE='GROUND';
      NO_LOAD_CHECK='Both';
      NO_IO_CHECK='Both';
      NO_ASSERT_CHECK='TRUE';
      NO_DIR_CHECK='TRUE';
      ALLOW_CONNECT='TRUE';
    'GND'<22>:
      PIN_NUMBER='(1A6)';
      PINUSE='GROUND';
      NO_LOAD_CHECK='Both';
      NO_IO_CHECK='Both';
      NO_ASSERT_CHECK='TRUE';
      NO_DIR_CHECK='TRUE';
      ALLOW_CONNECT='TRUE';
    'GND'<21>:
      PIN_NUMBER='(1A9)';
      PINUSE='GROUND';
      NO_LOAD_CHECK='Both';
      NO_IO_CHECK='Both';
      NO_ASSERT_CHECK='TRUE';
      NO_DIR_CHECK='TRUE';
      ALLOW_CONNECT='TRUE';
    'GND'<20>:
      PIN_NUMBER='(1B3)';
      PINUSE='GROUND';
      NO_LOAD_CHECK='Both';
      NO_IO_CHECK='Both';
      NO_ASSERT_CHECK='TRUE';
      NO_DIR_CHECK='TRUE';
      ALLOW_CONNECT='TRUE';
    'GND'<19>:
      PIN_NUMBER='(1B6)';
      PINUSE='GROUND';
      NO_LOAD_CHECK='Both';
      NO_IO_CHECK='Both';
      NO_ASSERT_CHECK='TRUE';
      NO_DIR_CHECK='TRUE';
      ALLOW_CONNECT='TRUE';
    'GND'<18>:
      PIN_NUMBER='(1B9)';
      PINUSE='GROUND';
      NO_LOAD_CHECK='Both';
      NO_IO_CHECK='Both';
      NO_ASSERT_CHECK='TRUE';
      NO_DIR_CHECK='TRUE';
      ALLOW_CONNECT='TRUE';
    'GND'<17>:
      PIN_NUMBER='(1C3)';
      PINUSE='GROUND';
      NO_LOAD_CHECK='Both';
      NO_IO_CHECK='Both';
      NO_ASSERT_CHECK='TRUE';
      NO_DIR_CHECK='TRUE';
      ALLOW_CONNECT='TRUE';
    'GND'<16>:
      PIN_NUMBER='(1C6)';
      PINUSE='GROUND';
      NO_LOAD_CHECK='Both';
      NO_IO_CHECK='Both';
      NO_ASSERT_CHECK='TRUE';
      NO_DIR_CHECK='TRUE';
      ALLOW_CONNECT='TRUE';
    'GND'<15>:
      PIN_NUMBER='(1C9)';
      PINUSE='GROUND';
      NO_LOAD_CHECK='Both';
      NO_IO_CHECK='Both';
      NO_ASSERT_CHECK='TRUE';
      NO_DIR_CHECK='TRUE';
      ALLOW_CONNECT='TRUE';
    'GND'<14>:
      PIN_NUMBER='(1D3)';
      PINUSE='GROUND';
      NO_LOAD_CHECK='Both';
      NO_IO_CHECK='Both';
      NO_ASSERT_CHECK='TRUE';
      NO_DIR_CHECK='TRUE';
      ALLOW_CONNECT='TRUE';
    'GND'<13>:
      PIN_NUMBER='(1D6)';
      BIDIRECTIONAL='TRUE';
      INPUT_LOAD='(-0.01,0.01)';
      OUTPUT_LOAD='(1.0,-1.0)';
    'GND'<12>:
      PIN_NUMBER='(1D9)';
      PINUSE='GROUND';
      NO_LOAD_CHECK='Both';
      NO_IO_CHECK='Both';
      NO_ASSERT_CHECK='TRUE';
      NO_DIR_CHECK='TRUE';
      ALLOW_CONNECT='TRUE';
    'GND'<11>:
      PIN_NUMBER='(2A3)';
      PINUSE='GROUND';
      NO_LOAD_CHECK='Both';
      NO_IO_CHECK='Both';
      NO_ASSERT_CHECK='TRUE';
      NO_DIR_CHECK='TRUE';
      ALLOW_CONNECT='TRUE';
    'GND'<10>:
      PIN_NUMBER='(2A6)';
      PINUSE='GROUND';
      NO_LOAD_CHECK='Both';
      NO_IO_CHECK='Both';
      NO_ASSERT_CHECK='TRUE';
      NO_DIR_CHECK='TRUE';
      ALLOW_CONNECT='TRUE';
    'GND'<9>:
      PIN_NUMBER='(2A9)';
      PINUSE='GROUND';
      NO_LOAD_CHECK='Both';
      NO_IO_CHECK='Both';
      NO_ASSERT_CHECK='TRUE';
      NO_DIR_CHECK='TRUE';
      ALLOW_CONNECT='TRUE';
    'GND'<8>:
      PIN_NUMBER='(2B3)';
      PINUSE='GROUND';
      NO_LOAD_CHECK='Both';
      NO_IO_CHECK='Both';
      NO_ASSERT_CHECK='TRUE';
      NO_DIR_CHECK='TRUE';
      ALLOW_CONNECT='TRUE';
    'GND'<7>:
      PIN_NUMBER='(2B6)';
      PINUSE='GROUND';
      NO_LOAD_CHECK='Both';
      NO_IO_CHECK='Both';
      NO_ASSERT_CHECK='TRUE';
      NO_DIR_CHECK='TRUE';
      ALLOW_CONNECT='TRUE';
    'GND'<6>:
      PIN_NUMBER='(2B9)';
      PINUSE='GROUND';
      NO_LOAD_CHECK='Both';
      NO_IO_CHECK='Both';
      NO_ASSERT_CHECK='TRUE';
      NO_DIR_CHECK='TRUE';
      ALLOW_CONNECT='TRUE';
    'GND'<5>:
      PIN_NUMBER='(2C3)';
      PINUSE='GROUND';
      NO_LOAD_CHECK='Both';
      NO_IO_CHECK='Both';
      NO_ASSERT_CHECK='TRUE';
      NO_DIR_CHECK='TRUE';
      ALLOW_CONNECT='TRUE';
    'GND'<4>:
      PIN_NUMBER='(2C6)';
      PINUSE='GROUND';
      NO_LOAD_CHECK='Both';
      NO_IO_CHECK='Both';
      NO_ASSERT_CHECK='TRUE';
      NO_DIR_CHECK='TRUE';
      ALLOW_CONNECT='TRUE';
    'GND'<3>:
      PIN_NUMBER='(2C9)';
      PINUSE='GROUND';
      NO_LOAD_CHECK='Both';
      NO_IO_CHECK='Both';
      NO_ASSERT_CHECK='TRUE';
      NO_DIR_CHECK='TRUE';
      ALLOW_CONNECT='TRUE';
    'GND'<2>:
      PIN_NUMBER='(2D3)';
      PINUSE='GROUND';
      NO_LOAD_CHECK='Both';
      NO_IO_CHECK='Both';
      NO_ASSERT_CHECK='TRUE';
      NO_DIR_CHECK='TRUE';
      ALLOW_CONNECT='TRUE';
    'GND'<1>:
      PIN_NUMBER='(2D6)';
      BIDIRECTIONAL='TRUE';
      INPUT_LOAD='(-0.01,0.01)';
      OUTPUT_LOAD='(1.0,-1.0)';
    'GND'<0>:
      PIN_NUMBER='(2D9)';
      PINUSE='GROUND';
      NO_LOAD_CHECK='Both';
      NO_IO_CHECK='Both';
      NO_ASSERT_CHECK='TRUE';
      NO_DIR_CHECK='TRUE';
      ALLOW_CONNECT='TRUE';
    'RXA0_DN':
      PIN_NUMBER='(1B5)';
      BIDIRECTIONAL='TRUE';
      INPUT_LOAD='(-0.01,0.01)';
      OUTPUT_LOAD='(1.0,-1.0)';
    'RXA0_DP':
      PIN_NUMBER='(1B4)';
      BIDIRECTIONAL='TRUE';
      INPUT_LOAD='(-0.01,0.01)';
      OUTPUT_LOAD='(1.0,-1.0)';
    'RXA1_DN':
      PIN_NUMBER='(1A5)';
      BIDIRECTIONAL='TRUE';
      INPUT_LOAD='(-0.01,0.01)';
      OUTPUT_LOAD='(1.0,-1.0)';
    'RXA1_DP':
      PIN_NUMBER='(1A4)';
      BIDIRECTIONAL='TRUE';
      INPUT_LOAD='(-0.01,0.01)';
      OUTPUT_LOAD='(1.0,-1.0)';
    'RXA2_DN':
      PIN_NUMBER='(1B8)';
      BIDIRECTIONAL='TRUE';
      INPUT_LOAD='(-0.01,0.01)';
      OUTPUT_LOAD='(1.0,-1.0)';
    'RXA2_DP':
      PIN_NUMBER='(1B7)';
      BIDIRECTIONAL='TRUE';
      INPUT_LOAD='(-0.01,0.01)';
      OUTPUT_LOAD='(1.0,-1.0)';
    'RXA3_DN':
      PIN_NUMBER='(1A8)';
      BIDIRECTIONAL='TRUE';
      INPUT_LOAD='(-0.01,0.01)';
      OUTPUT_LOAD='(1.0,-1.0)';
    'RXA3_DP':
      PIN_NUMBER='(1A7)';
      BIDIRECTIONAL='TRUE';
      INPUT_LOAD='(-0.01,0.01)';
      OUTPUT_LOAD='(1.0,-1.0)';
    'RXB0_DN':
      PIN_NUMBER='(2B5)';
      BIDIRECTIONAL='TRUE';
      INPUT_LOAD='(-0.01,0.01)';
      OUTPUT_LOAD='(1.0,-1.0)';
    'RXB0_DP':
      PIN_NUMBER='(2B4)';
      BIDIRECTIONAL='TRUE';
      INPUT_LOAD='(-0.01,0.01)';
      OUTPUT_LOAD='(1.0,-1.0)';
    'RXB1_DN':
      PIN_NUMBER='(2A5)';
      BIDIRECTIONAL='TRUE';
      INPUT_LOAD='(-0.01,0.01)';
      OUTPUT_LOAD='(1.0,-1.0)';
    'RXB1_DP':
      PIN_NUMBER='(2A4)';
      BIDIRECTIONAL='TRUE';
      INPUT_LOAD='(-0.01,0.01)';
      OUTPUT_LOAD='(1.0,-1.0)';
    'RXB2_DN':
      PIN_NUMBER='(2B8)';
      BIDIRECTIONAL='TRUE';
      INPUT_LOAD='(-0.01,0.01)';
      OUTPUT_LOAD='(1.0,-1.0)';
    'RXB2_DP':
      PIN_NUMBER='(2B7)';
      BIDIRECTIONAL='TRUE';
      INPUT_LOAD='(-0.01,0.01)';
      OUTPUT_LOAD='(1.0,-1.0)';
    'RXB3_DN':
      PIN_NUMBER='(2A8)';
      BIDIRECTIONAL='TRUE';
      INPUT_LOAD='(-0.01,0.01)';
      OUTPUT_LOAD='(1.0,-1.0)';
    'RXB3_DP':
      PIN_NUMBER='(2A7)';
      BIDIRECTIONAL='TRUE';
      INPUT_LOAD='(-0.01,0.01)';
      OUTPUT_LOAD='(1.0,-1.0)';
    'SIDEBANDA_0':
      PIN_NUMBER='(1A2)';
      BIDIRECTIONAL='TRUE';
      INPUT_LOAD='(-0.01,0.01)';
      OUTPUT_LOAD='(1.0,-1.0)';
    'SIDEBANDA_1':
      PIN_NUMBER='(1B2)';
      BIDIRECTIONAL='TRUE';
      INPUT_LOAD='(-0.01,0.01)';
      OUTPUT_LOAD='(1.0,-1.0)';
    'SIDEBANDA_2':
      PIN_NUMBER='(1C2)';
      BIDIRECTIONAL='TRUE';
      INPUT_LOAD='(-0.01,0.01)';
      OUTPUT_LOAD='(1.0,-1.0)';
    'SIDEBANDA_3':
      PIN_NUMBER='(1B1)';
      BIDIRECTIONAL='TRUE';
      INPUT_LOAD='(-0.01,0.01)';
      OUTPUT_LOAD='(1.0,-1.0)';
    'SIDEBANDA_4':
      PIN_NUMBER='(1C1)';
      BIDIRECTIONAL='TRUE';
      INPUT_LOAD='(-0.01,0.01)';
      OUTPUT_LOAD='(1.0,-1.0)';
    'SIDEBANDA_5':
      PIN_NUMBER='(1D1)';
      BIDIRECTIONAL='TRUE';
      INPUT_LOAD='(-0.01,0.01)';
      OUTPUT_LOAD='(1.0,-1.0)';
    'SIDEBANDA_6':
      PIN_NUMBER='(1D2)';
      BIDIRECTIONAL='TRUE';
      INPUT_LOAD='(-0.01,0.01)';
      OUTPUT_LOAD='(1.0,-1.0)';
    'SIDEBANDA_7':
      PIN_NUMBER='(1A1)';
      BIDIRECTIONAL='TRUE';
      INPUT_LOAD='(-0.01,0.01)';
      OUTPUT_LOAD='(1.0,-1.0)';
    'SIDEBANDB_0':
      PIN_NUMBER='(2A2)';
      BIDIRECTIONAL='TRUE';
      INPUT_LOAD='(-0.01,0.01)';
      OUTPUT_LOAD='(1.0,-1.0)';
    'SIDEBANDB_1':
      PIN_NUMBER='(2B2)';
      BIDIRECTIONAL='TRUE';
      INPUT_LOAD='(-0.01,0.01)';
      OUTPUT_LOAD='(1.0,-1.0)';
    'SIDEBANDB_2':
      PIN_NUMBER='(2C2)';
      BIDIRECTIONAL='TRUE';
      INPUT_LOAD='(-0.01,0.01)';
      OUTPUT_LOAD='(1.0,-1.0)';
    'SIDEBANDB_3':
      PIN_NUMBER='(2B1)';
      BIDIRECTIONAL='TRUE';
      INPUT_LOAD='(-0.01,0.01)';
      OUTPUT_LOAD='(1.0,-1.0)';
    'SIDEBANDB_4':
      PIN_NUMBER='(2C1)';
      BIDIRECTIONAL='TRUE';
      INPUT_LOAD='(-0.01,0.01)';
      OUTPUT_LOAD='(1.0,-1.0)';
    'SIDEBANDB_5':
      PIN_NUMBER='(2D1)';
      BIDIRECTIONAL='TRUE';
      INPUT_LOAD='(-0.01,0.01)';
      OUTPUT_LOAD='(1.0,-1.0)';
    'SIDEBANDB_6':
      PIN_NUMBER='(2D2)';
      BIDIRECTIONAL='TRUE';
      INPUT_LOAD='(-0.01,0.01)';
      OUTPUT_LOAD='(1.0,-1.0)';
    'SIDEBANDB_7':
      PIN_NUMBER='(2A1)';
      BIDIRECTIONAL='TRUE';
      INPUT_LOAD='(-0.01,0.01)';
      OUTPUT_LOAD='(1.0,-1.0)';
    'TXA0_DN':
      PIN_NUMBER='(1D5)';
      BIDIRECTIONAL='TRUE';
      INPUT_LOAD='(-0.01,0.01)';
      OUTPUT_LOAD='(1.0,-1.0)';
    'TXA0_DP':
      PIN_NUMBER='(1D4)';
      BIDIRECTIONAL='TRUE';
      INPUT_LOAD='(-0.01,0.01)';
      OUTPUT_LOAD='(1.0,-1.0)';
    'TXA1_DN':
      PIN_NUMBER='(1C5)';
      BIDIRECTIONAL='TRUE';
      INPUT_LOAD='(-0.01,0.01)';
      OUTPUT_LOAD='(1.0,-1.0)';
    'TXA1_DP':
      PIN_NUMBER='(1C4)';
      BIDIRECTIONAL='TRUE';
      INPUT_LOAD='(-0.01,0.01)';
      OUTPUT_LOAD='(1.0,-1.0)';
    'TXA2_DN':
      PIN_NUMBER='(1D8)';
      BIDIRECTIONAL='TRUE';
      INPUT_LOAD='(-0.01,0.01)';
      OUTPUT_LOAD='(1.0,-1.0)';
    'TXA2_DP':
      PIN_NUMBER='(1D7)';
      BIDIRECTIONAL='TRUE';
      INPUT_LOAD='(-0.01,0.01)';
      OUTPUT_LOAD='(1.0,-1.0)';
    'TXA3_DN':
      PIN_NUMBER='(1C8)';
      BIDIRECTIONAL='TRUE';
      INPUT_LOAD='(-0.01,0.01)';
      OUTPUT_LOAD='(1.0,-1.0)';
    'TXA3_DP':
      PIN_NUMBER='(1C7)';
      BIDIRECTIONAL='TRUE';
      INPUT_LOAD='(-0.01,0.01)';
      OUTPUT_LOAD='(1.0,-1.0)';
    'TXB0_DN':
      PIN_NUMBER='(2D5)';
      BIDIRECTIONAL='TRUE';
      INPUT_LOAD='(-0.01,0.01)';
      OUTPUT_LOAD='(1.0,-1.0)';
    'TXB0_DP':
      PIN_NUMBER='(2D4)';
      BIDIRECTIONAL='TRUE';
      INPUT_LOAD='(-0.01,0.01)';
      OUTPUT_LOAD='(1.0,-1.0)';
    'TXB1_DN':
      PIN_NUMBER='(2C5)';
      BIDIRECTIONAL='TRUE';
      INPUT_LOAD='(-0.01,0.01)';
      OUTPUT_LOAD='(1.0,-1.0)';
    'TXB1_DP':
      PIN_NUMBER='(2C4)';
      BIDIRECTIONAL='TRUE';
      INPUT_LOAD='(-0.01,0.01)';
      OUTPUT_LOAD='(1.0,-1.0)';
    'TXB2_DN':
      PIN_NUMBER='(2D8)';
      BIDIRECTIONAL='TRUE';
      INPUT_LOAD='(-0.01,0.01)';
      OUTPUT_LOAD='(1.0,-1.0)';
    'TXB2_DP':
      PIN_NUMBER='(2D7)';
      BIDIRECTIONAL='TRUE';
      INPUT_LOAD='(-0.01,0.01)';
      OUTPUT_LOAD='(1.0,-1.0)';
    'TXB3_DN':
      PIN_NUMBER='(2C8)';
      BIDIRECTIONAL='TRUE';
      INPUT_LOAD='(-0.01,0.01)';
      OUTPUT_LOAD='(1.0,-1.0)';
    'TXB3_DP':
      PIN_NUMBER='(2C7)';
      BIDIRECTIONAL='TRUE';
      INPUT_LOAD='(-0.01,0.01)';
      OUTPUT_LOAD='(1.0,-1.0)';
  end_pin;
  body
    PART_NAME='CONN72_G97614002_A';
    PHYS_DES_PREFIX='J';
  end_body;
end_primitive;

primitive 'CONN72_G97614002_A_BP';
  pin
    'GND'<23>:
      PIN_NUMBER='(1A3)';
      PINUSE='GROUND';
      NO_LOAD_CHECK='Both';
      NO_IO_CHECK='Both';
      NO_ASSERT_CHECK='TRUE';
      NO_DIR_CHECK='TRUE';
      ALLOW_CONNECT='TRUE';
    'GND'<22>:
      PIN_NUMBER='(1A6)';
      PINUSE='GROUND';
      NO_LOAD_CHECK='Both';
      NO_IO_CHECK='Both';
      NO_ASSERT_CHECK='TRUE';
      NO_DIR_CHECK='TRUE';
      ALLOW_CONNECT='TRUE';
    'GND'<21>:
      PIN_NUMBER='(1A9)';
      PINUSE='GROUND';
      NO_LOAD_CHECK='Both';
      NO_IO_CHECK='Both';
      NO_ASSERT_CHECK='TRUE';
      NO_DIR_CHECK='TRUE';
      ALLOW_CONNECT='TRUE';
    'GND'<20>:
      PIN_NUMBER='(1B3)';
      PINUSE='GROUND';
      NO_LOAD_CHECK='Both';
      NO_IO_CHECK='Both';
      NO_ASSERT_CHECK='TRUE';
      NO_DIR_CHECK='TRUE';
      ALLOW_CONNECT='TRUE';
    'GND'<19>:
      PIN_NUMBER='(1B6)';
      PINUSE='GROUND';
      NO_LOAD_CHECK='Both';
      NO_IO_CHECK='Both';
      NO_ASSERT_CHECK='TRUE';
      NO_DIR_CHECK='TRUE';
      ALLOW_CONNECT='TRUE';
    'GND'<18>:
      PIN_NUMBER='(1B9)';
      PINUSE='GROUND';
      NO_LOAD_CHECK='Both';
      NO_IO_CHECK='Both';
      NO_ASSERT_CHECK='TRUE';
      NO_DIR_CHECK='TRUE';
      ALLOW_CONNECT='TRUE';
    'GND'<17>:
      PIN_NUMBER='(1C3)';
      PINUSE='GROUND';
      NO_LOAD_CHECK='Both';
      NO_IO_CHECK='Both';
      NO_ASSERT_CHECK='TRUE';
      NO_DIR_CHECK='TRUE';
      ALLOW_CONNECT='TRUE';
    'GND'<16>:
      PIN_NUMBER='(1C6)';
      PINUSE='GROUND';
      NO_LOAD_CHECK='Both';
      NO_IO_CHECK='Both';
      NO_ASSERT_CHECK='TRUE';
      NO_DIR_CHECK='TRUE';
      ALLOW_CONNECT='TRUE';
    'GND'<15>:
      PIN_NUMBER='(1C9)';
      PINUSE='GROUND';
      NO_LOAD_CHECK='Both';
      NO_IO_CHECK='Both';
      NO_ASSERT_CHECK='TRUE';
      NO_DIR_CHECK='TRUE';
      ALLOW_CONNECT='TRUE';
    'GND'<14>:
      PIN_NUMBER='(1D3)';
      PINUSE='GROUND';
      NO_LOAD_CHECK='Both';
      NO_IO_CHECK='Both';
      NO_ASSERT_CHECK='TRUE';
      NO_DIR_CHECK='TRUE';
      ALLOW_CONNECT='TRUE';
    'GND'<13>:
      PIN_NUMBER='(1D6)';
      BIDIRECTIONAL='TRUE';
      INPUT_LOAD='(-0.01,0.01)';
      OUTPUT_LOAD='(1.0,-1.0)';
    'GND'<12>:
      PIN_NUMBER='(1D9)';
      PINUSE='GROUND';
      NO_LOAD_CHECK='Both';
      NO_IO_CHECK='Both';
      NO_ASSERT_CHECK='TRUE';
      NO_DIR_CHECK='TRUE';
      ALLOW_CONNECT='TRUE';
    'GND'<11>:
      PIN_NUMBER='(2A3)';
      PINUSE='GROUND';
      NO_LOAD_CHECK='Both';
      NO_IO_CHECK='Both';
      NO_ASSERT_CHECK='TRUE';
      NO_DIR_CHECK='TRUE';
      ALLOW_CONNECT='TRUE';
    'GND'<10>:
      PIN_NUMBER='(2A6)';
      PINUSE='GROUND';
      NO_LOAD_CHECK='Both';
      NO_IO_CHECK='Both';
      NO_ASSERT_CHECK='TRUE';
      NO_DIR_CHECK='TRUE';
      ALLOW_CONNECT='TRUE';
    'GND'<9>:
      PIN_NUMBER='(2A9)';
      PINUSE='GROUND';
      NO_LOAD_CHECK='Both';
      NO_IO_CHECK='Both';
      NO_ASSERT_CHECK='TRUE';
      NO_DIR_CHECK='TRUE';
      ALLOW_CONNECT='TRUE';
    'GND'<8>:
      PIN_NUMBER='(2B3)';
      PINUSE='GROUND';
      NO_LOAD_CHECK='Both';
      NO_IO_CHECK='Both';
      NO_ASSERT_CHECK='TRUE';
      NO_DIR_CHECK='TRUE';
      ALLOW_CONNECT='TRUE';
    'GND'<7>:
      PIN_NUMBER='(2B6)';
      PINUSE='GROUND';
      NO_LOAD_CHECK='Both';
      NO_IO_CHECK='Both';
      NO_ASSERT_CHECK='TRUE';
      NO_DIR_CHECK='TRUE';
      ALLOW_CONNECT='TRUE';
    'GND'<6>:
      PIN_NUMBER='(2B9)';
      PINUSE='GROUND';
      NO_LOAD_CHECK='Both';
      NO_IO_CHECK='Both';
      NO_ASSERT_CHECK='TRUE';
      NO_DIR_CHECK='TRUE';
      ALLOW_CONNECT='TRUE';
    'GND'<5>:
      PIN_NUMBER='(2C3)';
      PINUSE='GROUND';
      NO_LOAD_CHECK='Both';
      NO_IO_CHECK='Both';
      NO_ASSERT_CHECK='TRUE';
      NO_DIR_CHECK='TRUE';
      ALLOW_CONNECT='TRUE';
    'GND'<4>:
      PIN_NUMBER='(2C6)';
      PINUSE='GROUND';
      NO_LOAD_CHECK='Both';
      NO_IO_CHECK='Both';
      NO_ASSERT_CHECK='TRUE';
      NO_DIR_CHECK='TRUE';
      ALLOW_CONNECT='TRUE';
    'GND'<3>:
      PIN_NUMBER='(2C9)';
      PINUSE='GROUND';
      NO_LOAD_CHECK='Both';
      NO_IO_CHECK='Both';
      NO_ASSERT_CHECK='TRUE';
      NO_DIR_CHECK='TRUE';
      ALLOW_CONNECT='TRUE';
    'GND'<2>:
      PIN_NUMBER='(2D3)';
      PINUSE='GROUND';
      NO_LOAD_CHECK='Both';
      NO_IO_CHECK='Both';
      NO_ASSERT_CHECK='TRUE';
      NO_DIR_CHECK='TRUE';
      ALLOW_CONNECT='TRUE';
    'GND'<1>:
      PIN_NUMBER='(2D6)';
      BIDIRECTIONAL='TRUE';
      INPUT_LOAD='(-0.01,0.01)';
      OUTPUT_LOAD='(1.0,-1.0)';
    'GND'<0>:
      PIN_NUMBER='(2D9)';
      PINUSE='GROUND';
      NO_LOAD_CHECK='Both';
      NO_IO_CHECK='Both';
      NO_ASSERT_CHECK='TRUE';
      NO_DIR_CHECK='TRUE';
      ALLOW_CONNECT='TRUE';
    'RXA0_DN':
      PIN_NUMBER='(1B5)';
      BIDIRECTIONAL='TRUE';
      INPUT_LOAD='(-0.01,0.01)';
      OUTPUT_LOAD='(1.0,-1.0)';
    'RXA0_DP':
      PIN_NUMBER='(1B4)';
      BIDIRECTIONAL='TRUE';
      INPUT_LOAD='(-0.01,0.01)';
      OUTPUT_LOAD='(1.0,-1.0)';
    'RXA1_DN':
      PIN_NUMBER='(1A5)';
      BIDIRECTIONAL='TRUE';
      INPUT_LOAD='(-0.01,0.01)';
      OUTPUT_LOAD='(1.0,-1.0)';
    'RXA1_DP':
      PIN_NUMBER='(1A4)';
      BIDIRECTIONAL='TRUE';
      INPUT_LOAD='(-0.01,0.01)';
      OUTPUT_LOAD='(1.0,-1.0)';
    'RXA2_DN':
      PIN_NUMBER='(1B8)';
      BIDIRECTIONAL='TRUE';
      INPUT_LOAD='(-0.01,0.01)';
      OUTPUT_LOAD='(1.0,-1.0)';
    'RXA2_DP':
      PIN_NUMBER='(1B7)';
      BIDIRECTIONAL='TRUE';
      INPUT_LOAD='(-0.01,0.01)';
      OUTPUT_LOAD='(1.0,-1.0)';
    'RXA3_DN':
      PIN_NUMBER='(1A8)';
      BIDIRECTIONAL='TRUE';
      INPUT_LOAD='(-0.01,0.01)';
      OUTPUT_LOAD='(1.0,-1.0)';
    'RXA3_DP':
      PIN_NUMBER='(1A7)';
      BIDIRECTIONAL='TRUE';
      INPUT_LOAD='(-0.01,0.01)';
      OUTPUT_LOAD='(1.0,-1.0)';
    'RXB0_DN':
      PIN_NUMBER='(2B5)';
      BIDIRECTIONAL='TRUE';
      INPUT_LOAD='(-0.01,0.01)';
      OUTPUT_LOAD='(1.0,-1.0)';
    'RXB0_DP':
      PIN_NUMBER='(2B4)';
      BIDIRECTIONAL='TRUE';
      INPUT_LOAD='(-0.01,0.01)';
      OUTPUT_LOAD='(1.0,-1.0)';
    'RXB1_DN':
      PIN_NUMBER='(2A5)';
      BIDIRECTIONAL='TRUE';
      INPUT_LOAD='(-0.01,0.01)';
      OUTPUT_LOAD='(1.0,-1.0)';
    'RXB1_DP':
      PIN_NUMBER='(2A4)';
      BIDIRECTIONAL='TRUE';
      INPUT_LOAD='(-0.01,0.01)';
      OUTPUT_LOAD='(1.0,-1.0)';
    'RXB2_DN':
      PIN_NUMBER='(2B8)';
      BIDIRECTIONAL='TRUE';
      INPUT_LOAD='(-0.01,0.01)';
      OUTPUT_LOAD='(1.0,-1.0)';
    'RXB2_DP':
      PIN_NUMBER='(2B7)';
      BIDIRECTIONAL='TRUE';
      INPUT_LOAD='(-0.01,0.01)';
      OUTPUT_LOAD='(1.0,-1.0)';
    'RXB3_DN':
      PIN_NUMBER='(2A8)';
      BIDIRECTIONAL='TRUE';
      INPUT_LOAD='(-0.01,0.01)';
      OUTPUT_LOAD='(1.0,-1.0)';
    'RXB3_DP':
      PIN_NUMBER='(2A7)';
      BIDIRECTIONAL='TRUE';
      INPUT_LOAD='(-0.01,0.01)';
      OUTPUT_LOAD='(1.0,-1.0)';
    'SIDEBANDA_0':
      PIN_NUMBER='(1A1)';
      BIDIRECTIONAL='TRUE';
      INPUT_LOAD='(-0.01,0.01)';
      OUTPUT_LOAD='(1.0,-1.0)';
    'SIDEBANDA_1':
      PIN_NUMBER='(1B1)';
      BIDIRECTIONAL='TRUE';
      INPUT_LOAD='(-0.01,0.01)';
      OUTPUT_LOAD='(1.0,-1.0)';
    'SIDEBANDA_2':
      PIN_NUMBER='(1C1)';
      BIDIRECTIONAL='TRUE';
      INPUT_LOAD='(-0.01,0.01)';
      OUTPUT_LOAD='(1.0,-1.0)';
    'SIDEBANDA_3':
      PIN_NUMBER='(1B2)';
      BIDIRECTIONAL='TRUE';
      INPUT_LOAD='(-0.01,0.01)';
      OUTPUT_LOAD='(1.0,-1.0)';
    'SIDEBANDA_4':
      PIN_NUMBER='(1C2)';
      BIDIRECTIONAL='TRUE';
      INPUT_LOAD='(-0.01,0.01)';
      OUTPUT_LOAD='(1.0,-1.0)';
    'SIDEBANDA_5':
      PIN_NUMBER='(1D2)';
      BIDIRECTIONAL='TRUE';
      INPUT_LOAD='(-0.01,0.01)';
      OUTPUT_LOAD='(1.0,-1.0)';
    'SIDEBANDA_6':
      PIN_NUMBER='(1D1)';
      BIDIRECTIONAL='TRUE';
      INPUT_LOAD='(-0.01,0.01)';
      OUTPUT_LOAD='(1.0,-1.0)';
    'SIDEBANDA_7':
      PIN_NUMBER='(1A2)';
      BIDIRECTIONAL='TRUE';
      INPUT_LOAD='(-0.01,0.01)';
      OUTPUT_LOAD='(1.0,-1.0)';
    'SIDEBANDB_0':
      PIN_NUMBER='(2A1)';
      BIDIRECTIONAL='TRUE';
      INPUT_LOAD='(-0.01,0.01)';
      OUTPUT_LOAD='(1.0,-1.0)';
    'SIDEBANDB_1':
      PIN_NUMBER='(2B1)';
      BIDIRECTIONAL='TRUE';
      INPUT_LOAD='(-0.01,0.01)';
      OUTPUT_LOAD='(1.0,-1.0)';
    'SIDEBANDB_2':
      PIN_NUMBER='(2C1)';
      BIDIRECTIONAL='TRUE';
      INPUT_LOAD='(-0.01,0.01)';
      OUTPUT_LOAD='(1.0,-1.0)';
    'SIDEBANDB_3':
      PIN_NUMBER='(2B2)';
      BIDIRECTIONAL='TRUE';
      INPUT_LOAD='(-0.01,0.01)';
      OUTPUT_LOAD='(1.0,-1.0)';
    'SIDEBANDB_4':
      PIN_NUMBER='(2C2)';
      BIDIRECTIONAL='TRUE';
      INPUT_LOAD='(-0.01,0.01)';
      OUTPUT_LOAD='(1.0,-1.0)';
    'SIDEBANDB_5':
      PIN_NUMBER='(2D2)';
      BIDIRECTIONAL='TRUE';
      INPUT_LOAD='(-0.01,0.01)';
      OUTPUT_LOAD='(1.0,-1.0)';
    'SIDEBANDB_6':
      PIN_NUMBER='(2D1)';
      BIDIRECTIONAL='TRUE';
      INPUT_LOAD='(-0.01,0.01)';
      OUTPUT_LOAD='(1.0,-1.0)';
    'SIDEBANDB_7':
      PIN_NUMBER='(2A2)';
      BIDIRECTIONAL='TRUE';
      INPUT_LOAD='(-0.01,0.01)';
      OUTPUT_LOAD='(1.0,-1.0)';
    'TXA0_DN':
      PIN_NUMBER='(1D5)';
      BIDIRECTIONAL='TRUE';
      INPUT_LOAD='(-0.01,0.01)';
      OUTPUT_LOAD='(1.0,-1.0)';
    'TXA0_DP':
      PIN_NUMBER='(1D4)';
      BIDIRECTIONAL='TRUE';
      INPUT_LOAD='(-0.01,0.01)';
      OUTPUT_LOAD='(1.0,-1.0)';
    'TXA1_DN':
      PIN_NUMBER='(1C5)';
      BIDIRECTIONAL='TRUE';
      INPUT_LOAD='(-0.01,0.01)';
      OUTPUT_LOAD='(1.0,-1.0)';
    'TXA1_DP':
      PIN_NUMBER='(1C4)';
      BIDIRECTIONAL='TRUE';
      INPUT_LOAD='(-0.01,0.01)';
      OUTPUT_LOAD='(1.0,-1.0)';
    'TXA2_DN':
      PIN_NUMBER='(1D8)';
      BIDIRECTIONAL='TRUE';
      INPUT_LOAD='(-0.01,0.01)';
      OUTPUT_LOAD='(1.0,-1.0)';
    'TXA2_DP':
      PIN_NUMBER='(1D7)';
      BIDIRECTIONAL='TRUE';
      INPUT_LOAD='(-0.01,0.01)';
      OUTPUT_LOAD='(1.0,-1.0)';
    'TXA3_DN':
      PIN_NUMBER='(1C8)';
      BIDIRECTIONAL='TRUE';
      INPUT_LOAD='(-0.01,0.01)';
      OUTPUT_LOAD='(1.0,-1.0)';
    'TXA3_DP':
      PIN_NUMBER='(1C7)';
      BIDIRECTIONAL='TRUE';
      INPUT_LOAD='(-0.01,0.01)';
      OUTPUT_LOAD='(1.0,-1.0)';
    'TXB0_DN':
      PIN_NUMBER='(2D5)';
      BIDIRECTIONAL='TRUE';
      INPUT_LOAD='(-0.01,0.01)';
      OUTPUT_LOAD='(1.0,-1.0)';
    'TXB0_DP':
      PIN_NUMBER='(2D4)';
      BIDIRECTIONAL='TRUE';
      INPUT_LOAD='(-0.01,0.01)';
      OUTPUT_LOAD='(1.0,-1.0)';
    'TXB1_DN':
      PIN_NUMBER='(2C5)';
      BIDIRECTIONAL='TRUE';
      INPUT_LOAD='(-0.01,0.01)';
      OUTPUT_LOAD='(1.0,-1.0)';
    'TXB1_DP':
      PIN_NUMBER='(2C4)';
      BIDIRECTIONAL='TRUE';
      INPUT_LOAD='(-0.01,0.01)';
      OUTPUT_LOAD='(1.0,-1.0)';
    'TXB2_DN':
      PIN_NUMBER='(2D8)';
      BIDIRECTIONAL='TRUE';
      INPUT_LOAD='(-0.01,0.01)';
      OUTPUT_LOAD='(1.0,-1.0)';
    'TXB2_DP':
      PIN_NUMBER='(2D7)';
      BIDIRECTIONAL='TRUE';
      INPUT_LOAD='(-0.01,0.01)';
      OUTPUT_LOAD='(1.0,-1.0)';
    'TXB3_DN':
      PIN_NUMBER='(2C8)';
      BIDIRECTIONAL='TRUE';
      INPUT_LOAD='(-0.01,0.01)';
      OUTPUT_LOAD='(1.0,-1.0)';
    'TXB3_DP':
      PIN_NUMBER='(2C7)';
      BIDIRECTIONAL='TRUE';
      INPUT_LOAD='(-0.01,0.01)';
      OUTPUT_LOAD='(1.0,-1.0)';
  end_pin;
  body
    PART_NAME='CONN72_G97614002_A';
    PHYS_DES_PREFIX='J';
  end_body;
end_primitive;

END.
